(kicad_pcb
	(version 20260206)
	(generator "pcbnew")
	(generator_version "10.0")
	(general
		(thickness 1.6)
		(legacy_teardrops no)
	)
	(paper "A4")
	(title_block
		(title "01162023_DA0F0TEBIF0_F0T_Expander_BD_F_brd_V02_OCP.brd")
		(comment 1 "Grand Teton / footprints 2820-2824 of 9728")
	)
	(layers
		(0 "F.Cu" signal "TOP")
		(4 "In1.Cu" signal "GND")
		(6 "In2.Cu" signal "VCC")
		(8 "In3.Cu" signal "VCC1")
		(10 "In4.Cu" signal "GND1")
		(12 "In5.Cu" signal "IN1")
		(14 "In6.Cu" signal "GND2")
		(16 "In7.Cu" signal "IN2")
		(18 "In8.Cu" signal "GND3")
		(20 "In9.Cu" signal "IN3")
		(22 "In10.Cu" signal "GND4")
		(24 "In11.Cu" signal "IN4")
		(26 "In12.Cu" signal "GND5")
		(28 "In13.Cu" signal "IN5")
		(30 "In14.Cu" signal "GND6")
		(32 "In15.Cu" signal "IN6")
		(34 "In16.Cu" signal "GND7")
		(2 "B.Cu" signal "BOTTOM")
		(9 "F.Adhes" user "F.Adhesive")
		(11 "B.Adhes" user "B.Adhesive")
		(13 "F.Paste" user "Package Geometry/Pastemask Top")
		(15 "B.Paste" user "Package Geometry/Pastemask Bottom")
		(5 "F.SilkS" user "Ref Des/Silkscreen Top")
		(7 "B.SilkS" user "Ref Des/Silkscreen Bottom")
		(1 "F.Mask" user "Board Geometry/Soldermask Top")
		(3 "B.Mask" user "Board Geometry/Soldermask Bottom")
		(17 "Dwgs.User" user "User.Drawings")
		(19 "Cmts.User" user "User.Comments")
		(21 "Eco1.User" user "User.Eco1")
		(23 "Eco2.User" user "User.Eco2")
		(25 "Edge.Cuts" user "Board Geometry/Outline")
		(27 "Margin" user)
		(31 "F.CrtYd" user "Package Geometry/Place Bound Top")
		(29 "B.CrtYd" user "Package Geometry/Place Bound Bottom")
		(35 "F.Fab" user "Ref Des/Assembly Top")
		(33 "B.Fab" user "Ref Des/Assembly Bottom")
	)
	(footprint ""
		(layer "F.Cu")
		(at 303.698402 -66.32194 -90)
		(property "Reference" "PC871"
			(at 0 0 270)
			(layer "F.SilkS")
			(hide yes)
			(effects
				(font
					(size 1.27 1.27)
				)
			)
		)
		(property "Value" ""
			(at 0 0 270)
			(layer "F.Fab")
			(effects
				(font
					(size 1.27 1.27)
				)
			)
		)
		(duplicate_pad_numbers_are_jumpers no)
		(fp_line
			(start -0.7874 0.4064)
			(end -0.7874 -0.4064)
			(stroke
				(width 0.1524)
				(type default)
			)
			(layer "F.SilkS")
		)
		(fp_line
			(start 0.7874 0.4064)
			(end -0.7874 0.4064)
			(stroke
				(width 0.1524)
				(type default)
			)
			(layer "F.SilkS")
		)
		(fp_line
			(start -0.7874 -0.4064)
			(end 0.7874 -0.4064)
			(stroke
				(width 0.1524)
				(type default)
			)
			(layer "F.SilkS")
		)
		(fp_line
			(start 0.7874 -0.4064)
			(end 0.7874 0.4064)
			(stroke
				(width 0.1524)
				(type default)
			)
			(layer "F.SilkS")
		)
		(fp_line
			(start -0.67945 0.3048)
			(end -0.67945 -0.305054)
			(stroke
				(width 0.1)
				(type default)
			)
			(layer "F.Fab")
		)
		(fp_line
			(start -0.12065 0.3048)
			(end -0.67945 0.3048)
			(stroke
				(width 0.1)
				(type default)
			)
			(layer "F.Fab")
		)
		(fp_line
			(start 0.120396 0.3048)
			(end 0.120396 0.2794)
			(stroke
				(width 0.1)
				(type default)
			)
			(layer "F.Fab")
		)
		(fp_line
			(start 0.67945 0.3048)
			(end 0.120396 0.3048)
			(stroke
				(width 0.1)
				(type default)
			)
			(layer "F.Fab")
		)
		(fp_line
			(start -0.12065 0.2794)
			(end -0.12065 0.3048)
			(stroke
				(width 0.1)
				(type default)
			)
			(layer "F.Fab")
		)
		(fp_line
			(start 0.120396 0.2794)
			(end -0.12065 0.2794)
			(stroke
				(width 0.1)
				(type default)
			)
			(layer "F.Fab")
		)
		(fp_line
			(start -0.12065 -0.2794)
			(end 0.12065 -0.2794)
			(stroke
				(width 0.1)
				(type default)
			)
			(layer "F.Fab")
		)
		(fp_line
			(start 0.12065 -0.2794)
			(end 0.12065 -0.3048)
			(stroke
				(width 0.1)
				(type default)
			)
			(layer "F.Fab")
		)
		(fp_line
			(start 0.12065 -0.3048)
			(end 0.67945 -0.3048)
			(stroke
				(width 0.1)
				(type default)
			)
			(layer "F.Fab")
		)
		(fp_line
			(start 0.67945 -0.3048)
			(end 0.67945 0.3048)
			(stroke
				(width 0.1)
				(type default)
			)
			(layer "F.Fab")
		)
		(fp_line
			(start -0.67945 -0.305054)
			(end -0.12065 -0.305054)
			(stroke
				(width 0.1)
				(type default)
			)
			(layer "F.Fab")
		)
		(fp_line
			(start -0.12065 -0.305054)
			(end -0.12065 -0.2794)
			(stroke
				(width 0.1)
				(type default)
			)
			(layer "F.Fab")
		)
		(pad "1" smd circle
			(at -0.40005 0 270)
			(size 0 0)
			(layers "F.Cu" "F.Mask" "F.Paste")
			(net "P12V_SSD10_CO_GATE")
		)
		(pad "2" smd circle
			(at 0.40005 0 270)
			(size 0 0)
			(layers "F.Cu" "F.Mask" "F.Paste")
			(net "GND")
		)
	)
	(footprint ""
		(layer "F.Cu")
		(at 118.441978 -27.006296 -90)
		(property "Reference" "PR7108"
			(at 0 0 270)
			(layer "F.SilkS")
			(hide yes)
			(effects
				(font
					(size 1.27 1.27)
				)
			)
		)
		(property "Value" ""
			(at 0 0 270)
			(layer "F.Fab")
			(effects
				(font
					(size 1.27 1.27)
				)
			)
		)
		(duplicate_pad_numbers_are_jumpers no)
		(fp_line
			(start -0.7874 0.4064)
			(end -0.7874 -0.4064)
			(stroke
				(width 0.1524)
				(type default)
			)
			(layer "F.SilkS")
		)
		(fp_line
			(start 0.7874 0.4064)
			(end -0.7874 0.4064)
			(stroke
				(width 0.1524)
				(type default)
			)
			(layer "F.SilkS")
		)
		(fp_line
			(start -0.7874 -0.4064)
			(end 0.7874 -0.4064)
			(stroke
				(width 0.1524)
				(type default)
			)
			(layer "F.SilkS")
		)
		(fp_line
			(start 0.7874 -0.4064)
			(end 0.7874 0.4064)
			(stroke
				(width 0.1524)
				(type default)
			)
			(layer "F.SilkS")
		)
		(fp_line
			(start -0.67945 0.3048)
			(end -0.67945 -0.305054)
			(stroke
				(width 0.1)
				(type default)
			)
			(layer "F.Fab")
		)
		(fp_line
			(start -0.12065 0.3048)
			(end -0.67945 0.3048)
			(stroke
				(width 0.1)
				(type default)
			)
			(layer "F.Fab")
		)
		(fp_line
			(start 0.120396 0.3048)
			(end 0.120396 0.2794)
			(stroke
				(width 0.1)
				(type default)
			)
			(layer "F.Fab")
		)
		(fp_line
			(start 0.67945 0.3048)
			(end 0.120396 0.3048)
			(stroke
				(width 0.1)
				(type default)
			)
			(layer "F.Fab")
		)
		(fp_line
			(start -0.12065 0.2794)
			(end -0.12065 0.3048)
			(stroke
				(width 0.1)
				(type default)
			)
			(layer "F.Fab")
		)
		(fp_line
			(start 0.120396 0.2794)
			(end -0.12065 0.2794)
			(stroke
				(width 0.1)
				(type default)
			)
			(layer "F.Fab")
		)
		(fp_line
			(start -0.12065 -0.2794)
			(end 0.12065 -0.2794)
			(stroke
				(width 0.1)
				(type default)
			)
			(layer "F.Fab")
		)
		(fp_line
			(start 0.12065 -0.2794)
			(end 0.12065 -0.3048)
			(stroke
				(width 0.1)
				(type default)
			)
			(layer "F.Fab")
		)
		(fp_line
			(start 0.12065 -0.3048)
			(end 0.67945 -0.3048)
			(stroke
				(width 0.1)
				(type default)
			)
			(layer "F.Fab")
		)
		(fp_line
			(start 0.67945 -0.3048)
			(end 0.67945 0.3048)
			(stroke
				(width 0.1)
				(type default)
			)
			(layer "F.Fab")
		)
		(fp_line
			(start -0.67945 -0.305054)
			(end -0.12065 -0.305054)
			(stroke
				(width 0.1)
				(type default)
			)
			(layer "F.Fab")
		)
		(fp_line
			(start -0.12065 -0.305054)
			(end -0.12065 -0.2794)
			(stroke
				(width 0.1)
				(type default)
			)
			(layer "F.Fab")
		)
		(pad "1" smd circle
			(at -0.40005 0 270)
			(size 0 0)
			(layers "F.Cu" "F.Mask" "F.Paste")
			(net "P3V3_SSD4_CO_ILIMIT")
		)
		(pad "2" smd circle
			(at 0.40005 0 270)
			(size 0 0)
			(layers "F.Cu" "F.Mask" "F.Paste")
			(net "GND")
		)
	)
	(footprint ""
		(layer "F.Cu")
		(at 267.718286 -250.070874 -90)
		(property "Reference" "R1348"
			(at 0 0 270)
			(layer "F.SilkS")
			(hide yes)
			(effects
				(font
					(size 1.27 1.27)
				)
			)
		)
		(property "Value" ""
			(at 0 0 270)
			(layer "F.Fab")
			(effects
				(font
					(size 1.27 1.27)
				)
			)
		)
		(duplicate_pad_numbers_are_jumpers no)
		(fp_line
			(start -0.7874 0.4064)
			(end -0.7874 -0.4064)
			(stroke
				(width 0.1524)
				(type default)
			)
			(layer "F.SilkS")
		)
		(fp_line
			(start 0.7874 0.4064)
			(end -0.7874 0.4064)
			(stroke
				(width 0.1524)
				(type default)
			)
			(layer "F.SilkS")
		)
		(fp_line
			(start -0.7874 -0.4064)
			(end 0.7874 -0.4064)
			(stroke
				(width 0.1524)
				(type default)
			)
			(layer "F.SilkS")
		)
		(fp_line
			(start 0.7874 -0.4064)
			(end 0.7874 0.4064)
			(stroke
				(width 0.1524)
				(type default)
			)
			(layer "F.SilkS")
		)
		(fp_line
			(start -0.67945 0.3048)
			(end -0.67945 -0.305054)
			(stroke
				(width 0.1)
				(type default)
			)
			(layer "F.Fab")
		)
		(fp_line
			(start -0.12065 0.3048)
			(end -0.67945 0.3048)
			(stroke
				(width 0.1)
				(type default)
			)
			(layer "F.Fab")
		)
		(fp_line
			(start 0.120396 0.3048)
			(end 0.120396 0.2794)
			(stroke
				(width 0.1)
				(type default)
			)
			(layer "F.Fab")
		)
		(fp_line
			(start 0.67945 0.3048)
			(end 0.120396 0.3048)
			(stroke
				(width 0.1)
				(type default)
			)
			(layer "F.Fab")
		)
		(fp_line
			(start -0.12065 0.2794)
			(end -0.12065 0.3048)
			(stroke
				(width 0.1)
				(type default)
			)
			(layer "F.Fab")
		)
		(fp_line
			(start 0.120396 0.2794)
			(end -0.12065 0.2794)
			(stroke
				(width 0.1)
				(type default)
			)
			(layer "F.Fab")
		)
		(fp_line
			(start -0.12065 -0.2794)
			(end 0.12065 -0.2794)
			(stroke
				(width 0.1)
				(type default)
			)
			(layer "F.Fab")
		)
		(fp_line
			(start 0.12065 -0.2794)
			(end 0.12065 -0.3048)
			(stroke
				(width 0.1)
				(type default)
			)
			(layer "F.Fab")
		)
		(fp_line
			(start 0.12065 -0.3048)
			(end 0.67945 -0.3048)
			(stroke
				(width 0.1)
				(type default)
			)
			(layer "F.Fab")
		)
		(fp_line
			(start 0.67945 -0.3048)
			(end 0.67945 0.3048)
			(stroke
				(width 0.1)
				(type default)
			)
			(layer "F.Fab")
		)
		(fp_line
			(start -0.67945 -0.305054)
			(end -0.12065 -0.305054)
			(stroke
				(width 0.1)
				(type default)
			)
			(layer "F.Fab")
		)
		(fp_line
			(start -0.12065 -0.305054)
			(end -0.12065 -0.2794)
			(stroke
				(width 0.1)
				(type default)
			)
			(layer "F.Fab")
		)
		(pad "1" smd circle
			(at -0.40005 0 270)
			(size 0 0)
			(layers "F.Cu" "F.Mask" "F.Paste")
			(net "PEX2_MODE_SEL12")
		)
		(pad "2" smd circle
			(at 0.40005 0 270)
			(size 0 0)
			(layers "F.Cu" "F.Mask" "F.Paste")
			(net "P1V8_PEX")
		)
	)
	(footprint ""
		(layer "F.Cu")
		(at 312.759344 18.028412 180)
		(property "Reference" "DE03F_1"
			(at 2.853944 2.990342 0)
			(unlocked yes)
			(layer "F.SilkS")
			(effects
				(font
					(size 0.7874 0.5842)
					(thickness 0.1524)
				)
				(justify left)
			)
		)
		(property "Value" ""
			(at 0 0 180)
			(layer "F.Fab")
			(effects
				(font
					(size 1.27 1.27)
				)
			)
		)
		(duplicate_pad_numbers_are_jumpers no)
		(fp_line
			(start 1.2192 2.1082)
			(end -1.2192 2.1082)
			(stroke
				(width 0.1524)
				(type default)
			)
			(layer "F.SilkS")
		)
		(fp_line
			(start 1.2192 -2.1082)
			(end 1.2192 2.1082)
			(stroke
				(width 0.1524)
				(type default)
			)
			(layer "F.SilkS")
		)
		(fp_line
			(start -1.2192 2.1082)
			(end -1.2192 -2.1082)
			(stroke
				(width 0.1524)
				(type default)
			)
			(layer "F.SilkS")
		)
		(fp_line
			(start -1.2192 -2.1082)
			(end 1.2192 -2.1082)
			(stroke
				(width 0.1524)
				(type default)
			)
			(layer "F.SilkS")
		)
		(pad "" np_thru_hole circle
			(at -2.8829 -1.27 90)
			(size 1.0414 1.0414)
			(drill 1.0414)
			(layers "*.Cu" "*.Mask")
			(clearance 0.381)
			(thermal_gap 0.381)
		)
		(pad "" np_thru_hole circle
			(at -2.8829 1.27 90)
			(size 1.0414 1.0414)
			(drill 1.0414)
			(layers "*.Cu" "*.Mask")
			(clearance 0.381)
			(thermal_gap 0.381)
		)
		(pad "" np_thru_hole circle
			(at 3.4671 -1.27 90)
			(size 1.0414 1.0414)
			(drill 1.0414)
			(layers "*.Cu" "*.Mask")
			(clearance 0.381)
			(thermal_gap 0.381)
		)
		(pad "" np_thru_hole circle
			(at 3.4671 1.27 90)
			(size 1.0414 1.0414)
			(drill 1.0414)
			(layers "*.Cu" "*.Mask")
			(clearance 0.381)
			(thermal_gap 0.381)
		)
		(pad "1" smd rect
			(at 0.8255 -0.249936 90)
			(size 0.3048 0.508)
			(layers "F.Cu" "F.Mask" "F.Paste")
			(net "85_5INCH_IN1_DN")
		)
		(pad "2" smd rect
			(at 0.8255 0.249936 90)
			(size 0.3048 0.508)
			(layers "F.Cu" "F.Mask" "F.Paste")
			(net "85_5INCH_IN1_DP")
		)
		(pad "3" smd circle
			(at 0 0 180)
			(size 0 0)
			(layers "F.Cu" "F.Mask" "F.Paste")
			(net "COUPON_GND2")
		)
		(zone
			(layer "F.Cu")
			(hatch none 0.5)
			(connect_pads
				(clearance 0)
			)
			(min_thickness 0.25)
			(keepout
				(tracks not_allowed)
				(vias allowed)
				(pads allowed)
				(copperpour not_allowed)
				(footprints allowed)
			)
			(placement
				(enabled no)
				(sheetname "")
			)
			(fill
				(thermal_gap 0.5)
				(thermal_bridge_width 0.5)
				(island_removal_mode 0)
			)
			(polygon
				(pts
					(xy 311.641744 18.577052) (xy 311.641744 18.481548) (xy 312.238644 18.481548) (xy 312.238644 18.075148)
					(xy 311.641744 18.075148) (xy 311.641744 17.981676) (xy 312.238644 17.981676) (xy 312.238644 17.575276)
					(xy 311.641744 17.575276) (xy 311.641744 17.479772) (xy 312.340244 17.479772) (xy 312.340244 18.577052)
				)
			)
		)
		(zone
			(layers "F.Cu" "B.Cu" "In1.Cu" "In2.Cu" "In3.Cu" "In4.Cu" "In5.Cu" "In6.Cu"
				"In7.Cu" "In8.Cu" "In9.Cu" "In10.Cu" "In11.Cu" "In12.Cu" "In13.Cu" "In14.Cu"
				"In15.Cu" "In16.Cu"
			)
			(hatch none 0.5)
			(connect_pads
				(clearance 0)
			)
			(min_thickness 0.25)
			(keepout
				(tracks not_allowed)
				(vias allowed)
				(pads allowed)
				(copperpour not_allowed)
				(footprints allowed)
			)
			(placement
				(enabled no)
				(sheetname "")
			)
			(fill
				(thermal_gap 0.5)
				(thermal_bridge_width 0.5)
				(island_removal_mode 0)
			)
			(polygon
				(pts
					(arc
						(start 310.219344 16.758412)
						(mid 308.365144 16.758412)
						(end 310.219344 16.758412)
					)
				)
			)
		)
		(zone
			(layers "F.Cu" "B.Cu" "In1.Cu" "In2.Cu" "In3.Cu" "In4.Cu" "In5.Cu" "In6.Cu"
				"In7.Cu" "In8.Cu" "In9.Cu" "In10.Cu" "In11.Cu" "In12.Cu" "In13.Cu" "In14.Cu"
				"In15.Cu" "In16.Cu"
			)
			(hatch none 0.5)
			(connect_pads
				(clearance 0)
			)
			(min_thickness 0.25)
			(keepout
				(tracks not_allowed)
				(vias allowed)
				(pads allowed)
				(copperpour not_allowed)
				(footprints allowed)
			)
			(placement
				(enabled no)
				(sheetname "")
			)
			(fill
				(thermal_gap 0.5)
				(thermal_bridge_width 0.5)
				(island_removal_mode 0)
			)
			(polygon
				(pts
					(arc
						(start 310.219344 19.298412)
						(mid 308.365144 19.298412)
						(end 310.219344 19.298412)
					)
				)
			)
		)
		(zone
			(layers "F.Cu" "B.Cu" "In1.Cu" "In2.Cu" "In3.Cu" "In4.Cu" "In5.Cu" "In6.Cu"
				"In7.Cu" "In8.Cu" "In9.Cu" "In10.Cu" "In11.Cu" "In12.Cu" "In13.Cu" "In14.Cu"
				"In15.Cu" "In16.Cu"
			)
			(hatch none 0.5)
			(connect_pads
				(clearance 0)
			)
			(min_thickness 0.25)
			(keepout
				(tracks not_allowed)
				(vias allowed)
				(pads allowed)
				(copperpour not_allowed)
				(footprints allowed)
			)
			(placement
				(enabled no)
				(sheetname "")
			)
			(fill
				(thermal_gap 0.5)
				(thermal_bridge_width 0.5)
				(island_removal_mode 0)
			)
			(polygon
				(pts
					(arc
						(start 316.569344 16.758412)
						(mid 314.715144 16.758412)
						(end 316.569344 16.758412)
					)
				)
			)
		)
		(zone
			(layers "F.Cu" "B.Cu" "In1.Cu" "In2.Cu" "In3.Cu" "In4.Cu" "In5.Cu" "In6.Cu"
				"In7.Cu" "In8.Cu" "In9.Cu" "In10.Cu" "In11.Cu" "In12.Cu" "In13.Cu" "In14.Cu"
				"In15.Cu" "In16.Cu"
			)
			(hatch none 0.5)
			(connect_pads
				(clearance 0)
			)
			(min_thickness 0.25)
			(keepout
				(tracks not_allowed)
				(vias allowed)
				(pads allowed)
				(copperpour not_allowed)
				(footprints allowed)
			)
			(placement
				(enabled no)
				(sheetname "")
			)
			(fill
				(thermal_gap 0.5)
				(thermal_bridge_width 0.5)
				(island_removal_mode 0)
			)
			(polygon
				(pts
					(arc
						(start 316.569344 19.298412)
						(mid 314.715144 19.298412)
						(end 316.569344 19.298412)
					)
				)
			)
		)
	)
	(footprint ""
		(layer "F.Cu")
		(at 179.777644 -113.251742)
		(property "Reference" "R188"
			(at 0 0 0)
			(layer "F.SilkS")
			(hide yes)
			(effects
				(font
					(size 1.27 1.27)
				)
			)
		)
		(property "Value" ""
			(at 0 0 0)
			(layer "F.Fab")
			(effects
				(font
					(size 1.27 1.27)
				)
			)
		)
		(duplicate_pad_numbers_are_jumpers no)
		(fp_line
			(start -0.7874 -0.4064)
			(end 0.7874 -0.4064)
			(stroke
				(width 0.1524)
				(type default)
			)
			(layer "F.SilkS")
		)
		(fp_line
			(start -0.7874 0.4064)
			(end -0.7874 -0.4064)
			(stroke
				(width 0.1524)
				(type default)
			)
			(layer "F.SilkS")
		)
		(fp_line
			(start 0.7874 -0.4064)
			(end 0.7874 0.4064)
			(stroke
				(width 0.1524)
				(type default)
			)
			(layer "F.SilkS")
		)
		(fp_line
			(start 0.7874 0.4064)
			(end -0.7874 0.4064)
			(stroke
				(width 0.1524)
				(type default)
			)
			(layer "F.SilkS")
		)
		(fp_line
			(start -0.67945 -0.305054)
			(end -0.12065 -0.305054)
			(stroke
				(width 0.1)
				(type default)
			)
			(layer "F.Fab")
		)
		(fp_line
			(start -0.67945 0.3048)
			(end -0.67945 -0.305054)
			(stroke
				(width 0.1)
				(type default)
			)
			(layer "F.Fab")
		)
		(fp_line
			(start -0.12065 -0.305054)
			(end -0.12065 -0.2794)
			(stroke
				(width 0.1)
				(type default)
			)
			(layer "F.Fab")
		)
		(fp_line
			(start -0.12065 -0.2794)
			(end 0.12065 -0.2794)
			(stroke
				(width 0.1)
				(type default)
			)
			(layer "F.Fab")
		)
		(fp_line
			(start -0.12065 0.2794)
			(end -0.12065 0.3048)
			(stroke
				(width 0.1)
				(type default)
			)
			(layer "F.Fab")
		)
		(fp_line
			(start -0.12065 0.3048)
			(end -0.67945 0.3048)
			(stroke
				(width 0.1)
				(type default)
			)
			(layer "F.Fab")
		)
		(fp_line
			(start 0.120396 0.2794)
			(end -0.12065 0.2794)
			(stroke
				(width 0.1)
				(type default)
			)
			(layer "F.Fab")
		)
		(fp_line
			(start 0.120396 0.3048)
			(end 0.120396 0.2794)
			(stroke
				(width 0.1)
				(type default)
			)
			(layer "F.Fab")
		)
		(fp_line
			(start 0.12065 -0.3048)
			(end 0.67945 -0.3048)
			(stroke
				(width 0.1)
				(type default)
			)
			(layer "F.Fab")
		)
		(fp_line
			(start 0.12065 -0.2794)
			(end 0.12065 -0.3048)
			(stroke
				(width 0.1)
				(type default)
			)
			(layer "F.Fab")
		)
		(fp_line
			(start 0.67945 -0.3048)
			(end 0.67945 0.3048)
			(stroke
				(width 0.1)
				(type default)
			)
			(layer "F.Fab")
		)
		(fp_line
			(start 0.67945 0.3048)
			(end 0.120396 0.3048)
			(stroke
				(width 0.1)
				(type default)
			)
			(layer "F.Fab")
		)
		(pad "1" smd circle
			(at -0.40005 0)
			(size 0 0)
			(layers "F.Cu" "F.Mask" "F.Paste")
			(net "RST_SMB_NIC3_MUX_ISO_N")
		)
		(pad "2" smd circle
			(at 0.40005 0)
			(size 0 0)
			(layers "F.Cu" "F.Mask" "F.Paste")
			(net "P3V3_NIC3")
		)
	)
)
